FILE_TYPE = CONNECTIVITY;
{Allegro Design Entry HDL 16.6-p007 (v16-6-112F) 10/10/2012}
"PAGE_NUMBER" = 147;
0"NC";
1"VCC_ADCAV3V3\g"VOLTAGE"+3.3V"CDS_PHYS_NET_NAME"P3V3_STBY_BMC_ADCAV33";
2"GND\g";
3"GND\g";
4"P3V3_STBY\g";
5"GND\g";
6"P3V3_STBY\g";
7"GND\g";
8"GND\g";
9"GND\g";
10"GND\g";
11"GND\g";
12"A_P12V_STBY_SCALED";
13"A_P3V3_STBY_SCALED";
14"A_P3V_BAT_SCALED";
15"FAN_TACH3";
16"FM_POST_CARD_PRES_BMC_N";
17"FM_BOARD_SKU_ID1";
18"CLK_50M_CKMNG_BMC_1";
19"RMII_SPRNGVLLE_BMC_PCH_RXD0";
20"RMII_SPRNGVLLE_BMC_PCH_RXD1";
21"RMII_BMC_PCH_SPRNGVLLE_CRSDV";
22"RMII_BMC_PCH_SPRNGVLLE_RXER";
23"CLK_50M_CKMNG_BMC_2";
24"RMII_BMC_OCP_RXER";
25"RMII_BMC_OCP_RXD1";
26"RMII_BMC_OCP_RXD0";
27"FM_TPM_PRES_N";
28"FAN_TACH0";
29"FAN_TACH1";
30"FAN_TACH2";
31"FM_MP_PS_REDUNDANT_LOST_N";
32"FM_XRC_PRESENT_N";
33"FM_XRC_READY_N";
34"BMC_TPM_HW_RST";
35"BMC_UV_HIGH_SET";
36"FM_BOARD_SKU_ID0";
37"FM_BOARD_SKU_ID2";
38"FM_BOARD_SKU_ID3";
39"FM_BOARD_SKU_ID4";
40"H_CPU1_MEMKLM_MEMHOT_LVT3_BMC_N";
41"RMII_BMC_OCP_CRSDV";
42"FM_CPU0_PROC_ID0";
43"TP_RGMII1TXD3_GPIOT5";
44"RMII_BMC_OCP_TXEN_R";
45"H_CPU0_FAST_WAKE_LVT3_N"$PHYS_NET_NAME"H_CPU0_FAST_WAKE_LVT3_N"CDS_PHYS_NET_NAME"H_CPU0_FAST_WAKE_LVT3_N";
46"TP_RGMII1TXD2_GPIOT4";
48"RMII_BMC_OCP_TXD1_R";
47"RMII_BMC_OCP_TXD1_R";
50"RMII_BMC_PCH_SPRNGVLLE_TXD1_R";
49"RMII_BMC_PCH_SPRNGVLLE_TXD1_R";
51"TP_RGMII2TXD2_GPIOT4";
52"TP_RGMII2TXD3_GPIOT5";
53"RMII_BMC_SPRNGVLLE_TXEN_R";
54"FM_FORCE_ADR_N";
55"FM_UV_ADR_TRIGGER_EN";
57"RMII_BMC_PCH_SPRNGVLLE_TXD0_R";
56"RMII_BMC_PCH_SPRNGVLLE_TXD0_R";
59"RMII_BMC_OCP_TXD0_R";
58"RMII_BMC_OCP_TXD0_R";
60"A_P5V_STBY_SCALED";
61"FM_UARTSW_MSB_N";
62"A_P5V_SCALED";
63"RMII_BMC_OCP_TXEN";
64"A_PVNN_STBY_PCH_SENSOR";
65"A_P3V3_SCALED";
66"FM_UARTSW_LSB_N";
67"FM_CPLD_BMC_PWRDN_N"PHYS_NET_NAME"FM_CPLD_BMC_PWRDN_N"CDS_PHYS_NET_NAME"FM_CPLD_BMC_PWRDN_N";
68"FM_CPU_MSMI_LVT3_N";
69"FAN_PWM_OUT_SYS1";
70"A_P1V05_STBY_PCH_SENSOR";
71"FM_BACKUP_BIOS_SEL_N";
72"FM_BIOS_PREFRB2_GOOD";
73"FM_CPU0_PROC_ID1";
74"RMII_BMC_OCP_TXD0";
75"RMII_BMC_OCP_TXD1";
76"RMII_BMC_PCH_SPRNGVLLE_TXEN";
77"RMII_BMC_PCH_SPRNGVLLE_TXD1";
78"RMII_BMC_PCH_SPRNGVLLE_TXD0";
79"FAN_PWM_OUT_SYS0";
80"P3V3_STBY_BMC_ADCVREFP"VOLTAGE"+3.3V";
81"PD_ADCREXT"CDS_PHYS_NET_NAME"PD_ADCREXT";
82"P3V3_STBY_BMC_ADCVREFN"VOLTAGE"+3.3V";
%"AST2520A1-GP-GP"
"6","(-1825,3400)","0","w_hdl","I106";
;
CDS_SEC"6"
$SEC"6"
CDS_LOCATION"U25W4"
CDS_LIB"w_hdl"
PART_NUMBER"071.2520A.M001"
PACK_TYPE"ASIC2-GB1"
CDS_LMAN_SYM_OUTLINE"-1400,1400,1400,-1400"
VALUE"AST2520A1-GP-GP"
LOCATION"U25W4";
"RGMII2RXCK_RMII2RCLKI_GPIOV2"
$PN"C2"23;
"RGMII2RXD3_RMII2RXER_GPIOV7"
$PN"E6"22;
"RGMII2RXD2_RMII2CRSDV_GPIOV6"
$PN"D2"21;
"RGMII2RXD1_RMII2RXD1_GPIOV5"
$PN"D1"20;
"RGMII2RXD0_RMII2RXD0_GPIOV4"
$PN"C3"19;
"RGMII1RXCK_RMII1RCLKI_GPIOU4"
$PN"B4"18;
"RGMII1RXCTL_GPIOU5"
$PN"A4"40;
"RGMII1RXD3_RMII1RXER_GPIOV1"
$PN"C4"24;
"RGMII1RXD2_RMII1CRSDV_GPIOV0"
$PN"C5"41;
"RGMII1RXD1_RMII1RXD1_GPIOU7"
$PN"D6"25;
"RGMII1RXD0_RMII1RXD0_GPIOU6"
$PN"A3"26;
"GPIOR7_MDIO1"
$PN"E10"73;
"GPIOR6_MDC1"
$PN"D8"42;
"RGMII2RXCTL_GPIOV3"
$PN"C1"5;
"RGMII1TXD1_RMII1TXD1_GPIOT3"
$PN"A5"48,47;
"RGMII1TXD0_RMII1TXD0_GPIOT2"
$PN"F9"59,58;
"RGMII1TXD3_GPIOT5"
$PN"D7"43;
"RGMII1TXD2_GPIOT4"
$PN"E7"46;
"RGMII1TXCTL_RMII1TXEN_GPIOT1"
$PN"E9"44;
"RGMII1TXCK_RMII1RCLKO_GPIOT0"
$PN"B5"45;
"RGMII2TXD0_RMII2TXD0_GPIOU0"
$PN"A2"57,56;
"RGMII2TXD1_RMII2TXD1_GPIOU1"
$PN"B3"50,49;
"RGMII2TXD3_GPIOU3"
$PN"D4"52;
"RGMII2TXD2_GPIOU2"
$PN"D5"51;
"RGMII2TXCK_RMII2RCLKO_GPIOT6"
$PN"B2"0;
"RGMII2TXCTL_RMII2TXEN_GPIOT7"
$PN"B1"53;
"GPIOO0_TACH0_VPIG8"
$PN"U5"28;
"GPIOO2_TACH2"
$PN"V5"30;
"GPIOO1_TACH1_VPIG9"
$PN"U4"29;
"GPIOO3_TACH3"
$PN"AB4"15;
"GPIOO5_TACH5_VPIR3"
$PN"Y4"31;
"GPIOO4_TACH4_VPIR2"
$PN"AB3"16;
"GPIOP0_TACH8_VPIR6"
$PN"V4"34;
"GPIOO7_TACH7_VPIR5"
$PN"W4"33;
"GPIOO6_TACH6_VPIR4"
$PN"AA4"32;
"GPIOP1_TACH9_VPIR7"
$PN"W5"35;
"GPIOP2_TACH10_VPIR8"
$PN"AA5"36;
"GPIOP5_TACH13"
$PN"Y5"38;
"GPIOP4_TACH12"
$PN"Y6"37;
"GPIOP3_TACH11_VPIR9"
$PN"AB5"17;
"GPIOP6_TACH14"
$PN"W6"39;
"GPIOP7_TACH15"
$PN"V6"27;
"ADC0_GPIW0"
$PN"F4"60;
"ADC1_GPIW1"
$PN"F5"65;
"ADC2_GPIW2"
$PN"E2"64;
"ADC3_GPIW3"
$PN"E1"70;
"ADC5_GPIW5"
$PN"E3"12;
"ADC4_GPIW4"
$PN"F3"62;
"ADC6_GPIW6"
$PN"G5"13;
"ADC10_GPIX2"
$PN"G2"0;
"ADC9_GPIX1"
$PN"G3"0;
"ADC11_GPIX3"
$PN"F1"0;
"ADC12_GPIX4"
$PN"H5"0;
"ADC13_GPIX5"
$PN"G1"0;
"ADC15_GPIX7"
$PN"H4"0;
"ADC14_GPIX6"
$PN"H3"0;
"ADCVREFN"
$PN"H1"82;
"ADCREXT"
$PN"J1"81;
"ADCVREFP"
$PN"H2"80;
"GPION0_PWM0"
$PN"V2"79;
"GPION2_PWM2_VPIG2"
$PN"V3"72;
"GPION1_PWM1"
$PN"W2"69;
"GPION3_PWM3_VPIG3"
$PN"U3"68;
"GPION5_PWM5_VPIG5"
$PN"AA3"67;
"GPION4_PWM4_VPIG4"
$PN"W3"71;
"GPION7_PWM7_VPIG7"
$PN"T4"61;
"GPION6_PWM6_VPIG6"
$PN"Y3"66;
"RGMIICK"
$PN"D3"5;
"GPIOA7_TIMER8_MDIO2"
$PN"B13"55;
"GPIOA6_TIMER7_MDC2"
$PN"C13"54;
"ADC7_GPIW7"
$PN"G4"14;
"ADC8_GPIX0"
$PN"F2"0;
%"W_VCC_CIRCLE"
"1","(2350,2525)","0","w_power","I20";
;
BODY_TYPE"PLUMBING"
CDS_LMAN_SYM_OUTLINE"-100,100,100,-100"
CDS_LIB"w_power"
HDL_POWER"VCC_ADCAV3V3";
"VCC_CIRCLE \B"1;
%"RES"
"1","(925,4200)","0","mstr_discrete","I21";
;
CDS_LOCATION"R25W90"
MATERIAL"CHIP"
CDS_SEC"1"
WATTAGE"1/16W"
PACK_TYPE"0402"
ROOM"BMC"
BOM_COST"SM_CONTROLLER"
PART_NUMBER"G21796-250"
SEC"1"
SEC_TYPE"0402"
CDS_LIB"mstr_discrete"
LOCATION"R25W90"
TOLERANCE"1.0%"
VALUE"22.1";
"B"
$PN"2"77;
"A"
$PN"1"50,49;
%"RES"
"1","(925,4150)","0","mstr_discrete","I22";
;
CDS_LOCATION"R25W89"
MATERIAL"CHIP"
CDS_SEC"1"
WATTAGE"1/16W"
PACK_TYPE"0402"
PART_NUMBER"G21796-250"
SEC"1"
SEC_TYPE"0402"
CDS_LIB"mstr_discrete"
ROOM"BMC"
BOM_COST"SM_CONTROLLER"
TOLERANCE"1.0%"
VALUE"22.1"
LOCATION"R25W89";
"B"
$PN"2"78;
"A"
$PN"1"57,56;
%"RES"
"1","(875,4000)","0","mstr_discrete","I23";
;
CDS_LOCATION"R25W85"
BOM_COST"SM_CONTROLLER"
SEC_TYPE"0402"
SEC"1"
PART_NUMBER"G21796-250"
PACK_TYPE"0402"
CDS_LIB"mstr_discrete"
ROOM"BMC"
WATTAGE"1/16W"
CDS_SEC"1"
MATERIAL"CHIP"
LOCATION"R25W85"
VALUE"22.1"
TOLERANCE"1.0%";
"B"
$PN"2"63;
"A"
$PN"1"44;
%"RES"
"1","(875,3750)","0","mstr_discrete","I24";
;
CDS_LOCATION"R25W86"
MATERIAL"CHIP"
CDS_SEC"1"
WATTAGE"1/16W"
PART_NUMBER"G21796-250"
SEC"1"
SEC_TYPE"0402"
PACK_TYPE"0402"
CDS_LIB"mstr_discrete"
ROOM"BMC"
BOM_COST"SM_CONTROLLER"
LOCATION"R25W86"
TOLERANCE"1.0%"
VALUE"22.1";
"B"
$PN"2"74;
"A"
$PN"1"59,58;
%"RES"
"1","(875,3800)","0","mstr_discrete","I25";
;
CDS_LOCATION"R25W87"
PACK_TYPE"0402"
CDS_LIB"mstr_discrete"
SEC_TYPE"0402"
SEC"1"
PART_NUMBER"G21796-250"
BOM_COST"SM_CONTROLLER"
ROOM"BMC"
WATTAGE"1/16W"
CDS_SEC"1"
MATERIAL"CHIP"
LOCATION"R25W87"
TOLERANCE"1.0%"
VALUE"22.1";
"B"
$PN"2"75;
"A"
$PN"1"48,47;
%"RES"
"2","(2200,4750)","0","mstr_discrete","I3";
;
CDS_LOCATION"R25W92"
ROOM"BMC"
SEC"1"
BOM_COST"SM_CONTROLLER"
SEC_TYPE"0402"
CDS_LIB"mstr_discrete"
CDS_SEC"1"
LOCATION"R25W92"
VALUE"10.0K"
WATTAGE"1/16W"
MATERIAL"CHIP"
PART_NUMBER"G21796-016"
PACK_TYPE"0402"
TOLERANCE"1%";
"A"
$PN"1"6;
"B"
$PN"2"77;
%"CAP"
"1","(2000,2300)","1","mstr_discrete","I36";
;
CDS_LOCATION"C25W7"
CDS_SEC"1"
$SEC"1"
BOM_COST"SM_CONTROLLER"
ROOM"BMC"
CDS_LIB"mstr_discrete"
VALUE"0.1UF"
PART_NUMBER"A36096-030"
VOLTAGE"16V"
PACK_TYPE"0402"
MATERIAL"EMPTY"
LOCATION"C25W7"
TOLERANCE"10%";
"A"
$PN"1"80;
"B"
$PN"2"1;
%"GND"
"1","(2325,1850)","2","mstr_symbols","I37";
;
HDL_POWER"GND"
BODY_TYPE"PLUMBING"
CDS_LIB"mstr_symbols"
SIZE"1B"
VOLTAGE"0.0V";
"A\NAC"2;
%"CAP"
"2","(2000,1950)","0","mstr_discrete","I38";
;
CDS_LOCATION"C25W8"
CDS_SEC"1"
SEC"1"
SEC_TYPE"0402"
CDS_LIB"mstr_discrete"
ROOM"BMC"
BOM_COST"SM_CONTROLLER"
PACK_TYPE"0402"
MATERIAL"EMPTY"
PART_NUMBER"A36096-030"
TOLERANCE"10%"
VALUE"0.1UF"
LOCATION"C25W8"
VOLTAGE"16V";
"A"
$PN"1"82;
"B"
$PN"2"2;
%"CAP"
"2","(1625,2125)","1","mstr_discrete","I39";
;
CDS_LOCATION"C25W9"
CDS_LIB"mstr_discrete"
BOM_COST"SM_CONTROLLER"
SEC_TYPE"0402"
ROOM"BMC"
SEC"1"
CDS_SEC"1"
TOLERANCE"10%"
PACK_TYPE"0402"
VALUE"0.1UF"
VOLTAGE"16V"
LOCATION"C25W9"
MATERIAL"EMPTY"
PART_NUMBER"A36096-030";
"A"
$PN"1"82;
"B"
$PN"2"80;
%"RES"
"2","(1950,4775)","0","mstr_discrete","I4";
;
CDS_LOCATION"R25W91"
CDS_SEC"1"
CDS_LIB"mstr_discrete"
BOM_COST"SM_CONTROLLER"
ROOM"BMC"
SEC"1"
SEC_TYPE"0402"
LOCATION"R25W91"
PACK_TYPE"0402"
PART_NUMBER"G21796-016"
MATERIAL"CHIP"
TOLERANCE"1%"
VALUE"10.0K"
WATTAGE"1/16W";
"A"
$PN"1"6;
"B"
$PN"2"78;
%"RES"
"2","(775,1925)","6","mstr_discrete","I40";
;
CDS_LOCATION"R25W57"
CDS_SEC"1"
CDS_LIB"mstr_discrete"
SEC_TYPE"0402"
SEC"1"
BOM_COST"SM_CONTROLLER"
ROOM"BMC"
PART_NUMBER"G21796-344"
PACK_TYPE"0402"
VALUE"2.7K"
LOCATION"R25W57"
TOLERANCE"1%"
MATERIAL"CHIP"
WATTAGE"1/16W";
"A"
$PN"1"3;
"B"
$PN"2"81;
%"GND"
"1","(775,1675)","0","mstr_symbols","I41";
;
HDL_POWER"GND"
BODY_TYPE"PLUMBING"
VOLTAGE"0.0V"
CDS_LIB"mstr_symbols"
SIZE"1B";
"A\NAC"3;
%"RES"
"2","(-3650,4800)","0","mstr_discrete","I42";
;
CDS_SEC"1"
CDS_LOCATION"R25W79"
ROOM"BMC"
SEC"1"
SEC_TYPE"0402"
BOM_COST"SM_CONTROLLER"
CDS_LIB"mstr_discrete"
PACK_TYPE"0402"
MATERIAL"CHIP"
WATTAGE"1/16W"
TOLERANCE"1%"
VALUE"10.0K"
LOCATION"R25W79"
PART_NUMBER"G21796-016";
"A"
$PN"1"4;
"B"
$PN"2"19;
%"RES"
"2","(-3900,4800)","0","mstr_discrete","I43";
;
CDS_SEC"1"
CDS_LIB"mstr_discrete"
BOM_COST"SM_CONTROLLER"
SEC_TYPE"0402"
SEC"1"
ROOM"BMC"
CDS_LOCATION"R25W80"
PART_NUMBER"G21796-016"
VALUE"10.0K"
LOCATION"R25W80"
WATTAGE"1/16W"
PACK_TYPE"0402"
MATERIAL"CHIP"
TOLERANCE"1%";
"A"
$PN"1"4;
"B"
$PN"2"20;
%"P3V3_STBY"
"1","(-3900,5100)","0","mstr_symbols","I44";
;
SIZE"1B"
CDS_LIB"mstr_symbols"
VOLTAGE"3.3V"
BODY_TYPE"PLUMBING"
HDL_POWER"P3V3_STBY";
"G\NAC"4;
%"GND"
"1","(-3525,3600)","0","mstr_symbols","I46";
;
SIZE"1B"
VOLTAGE"0.0V"
CDS_LIB"mstr_symbols"
BODY_TYPE"PLUMBING"
HDL_POWER"GND";
"A\NAC"5;
%"P3V3_STBY"
"1","(1950,5100)","0","mstr_symbols","I5";
;
HDL_POWER"P3V3_STBY"
BODY_TYPE"PLUMBING"
VOLTAGE"3.3V"
SIZE"1B"
CDS_LIB"mstr_symbols";
"G\NAC"6;
%"RES"
"2","(-3525,1950)","0","mstr_discrete","I61";
;
CDS_SEC"1"
CDS_LIB"mstr_discrete"
CDS_LOCATION"R1U1"
SEC"1"
SEC_TYPE"0402"
PACK_TYPE"0402"
MATERIAL"CHIP"
LOCATION"R1U1"
VALUE"100.0K"
TOLERANCE"1%"
WATTAGE"1/16W"
PART_NUMBER"G21796-010";
"A"
$PN"1"15;
"B"
$PN"2"7;
%"RES"
"2","(-3775,1950)","0","mstr_discrete","I62";
;
CDS_SEC"1"
CDS_LIB"mstr_discrete"
CDS_LOCATION"R1U2"
SEC_TYPE"0402"
SEC"1"
PACK_TYPE"0402"
PART_NUMBER"G21796-010"
MATERIAL"CHIP"
WATTAGE"1/16W"
TOLERANCE"1%"
VALUE"100.0K"
LOCATION"R1U2";
"A"
$PN"1"30;
"B"
$PN"2"8;
%"GND"
"1","(-3525,1725)","0","mstr_symbols","I63";
;
HDL_POWER"GND"
BODY_TYPE"PLUMBING"
CDS_LIB"mstr_symbols"
VOLTAGE"0.0V"
SIZE"1B";
"A\NAC"7;
%"GND"
"1","(-3775,1725)","0","mstr_symbols","I64";
;
HDL_POWER"GND"
BODY_TYPE"PLUMBING"
VOLTAGE"0.0V"
CDS_LIB"mstr_symbols"
SIZE"1B";
"A\NAC"8;
%"RES"
"2","(-4025,1950)","0","mstr_discrete","I65";
;
CDS_SEC"1"
SEC_TYPE"0402"
SEC"1"
CDS_LOCATION"R1U4"
CDS_LIB"mstr_discrete"
MATERIAL"CHIP"
VALUE"100.0K"
PACK_TYPE"0402"
WATTAGE"1/16W"
TOLERANCE"1%"
PART_NUMBER"G21796-010"
LOCATION"R1U4";
"A"
$PN"1"29;
"B"
$PN"2"9;
%"RES"
"2","(-4275,1950)","0","mstr_discrete","I66";
;
CDS_SEC"1"
SEC"1"
SEC_TYPE"0402"
CDS_LOCATION"R1U5"
CDS_LIB"mstr_discrete"
PACK_TYPE"0402"
LOCATION"R1U5"
MATERIAL"CHIP"
PART_NUMBER"G21796-010"
WATTAGE"1/16W"
TOLERANCE"1%"
VALUE"100.0K";
"A"
$PN"1"28;
"B"
$PN"2"10;
%"GND"
"1","(-4025,1725)","0","mstr_symbols","I67";
;
HDL_POWER"GND"
BODY_TYPE"PLUMBING"
SIZE"1B"
VOLTAGE"0.0V"
CDS_LIB"mstr_symbols";
"A\NAC"9;
%"GND"
"1","(-4275,1725)","0","mstr_symbols","I68";
;
HDL_POWER"GND"
BODY_TYPE"PLUMBING"
SIZE"1B"
CDS_LIB"mstr_symbols"
VOLTAGE"0.0V";
"A\NAC"10;
%"RES"
"2","(-100,1825)","0","mstr_discrete","I75";
;
CDS_SEC"1"
$SEC"1"
CDS_LOCATION"R2N13"
CDS_LIB"mstr_discrete"
ROOM"BMC"
BOM_COST"SM_CONTROLLER"
LOCATION"R2N13"
VALUE"10.0K"
TOLERANCE"1%"
WATTAGE"1/16W"
MATERIAL"CHIP"
PART_NUMBER"G21796-016"
PACK_TYPE"0402";
"A"
$PN"1"72;
"B"
$PN"2"11;
%"GND"
"1","(-100,1575)","0","mstr_symbols","I76";
;
HDL_POWER"GND"
BODY_TYPE"PLUMBING"
VOLTAGE"0.0V"
SIZE"1B"
CDS_LIB"mstr_symbols";
"A\NAC"11;
%"RES"
"1","(925,4400)","0","mstr_discrete","I8";
;
CDS_LOCATION"R25W88"
CDS_SEC"1"
WATTAGE"1/16W"
PART_NUMBER"G21796-250"
SEC"1"
SEC_TYPE"0402"
ROOM"BMC"
CDS_LIB"mstr_discrete"
BOM_COST"SM_CONTROLLER"
PACK_TYPE"0402"
MATERIAL"CHIP"
LOCATION"R25W88"
VALUE"22.1"
TOLERANCE"1.0%";
"B"
$PN"2"76;
"A"
$PN"1"53;
END.
